# BASEBOARD_FAB2 (Tioga Pass) — schematic netlist excerpt (pin names and nets, part order shuffled) for the footprints in the layout excerpt that follows; sources: Cadence DE-HDL packaged netlist, KiCad conversion of Wiwynn_Tioga_Pass_MB.brd

RN8F4  RES  4.75K 1% EMPTY  pkg 0402  page 246 : A = P3V3_STBY ; B = PU_TPM_SPI_FLASH_RESET_2_N
C3N16  CAP_A  1.0UF 6.3V 10% X6S  pkg 0402V  page 132 : A = PVNN_PCH_STBY ; B = GND
R25W169  RES  1.00K 1% CHIP  pkg 0402  page 254 : A = JTAG_BMC_TCK1 ; B = GND

(kicad_pcb
	(version 20260206)
	(generator "pcbnew")
	(generator_version "10.0")
	(general
		(thickness 1.6)
		(legacy_teardrops no)
	)
	(paper "A4")
	(title_block
		(title "Wiwynn_Tioga_Pass_MB.brd")
		(comment 1 "Tioga Pass / footprints 2685-2687 of 4770")
	)
	(layers
		(0 "F.Cu" signal "TOP")
		(4 "In1.Cu" signal "L2GND")
		(6 "In2.Cu" signal "L3")
		(8 "In3.Cu" signal "L4GND")
		(10 "In4.Cu" signal "L5")
		(12 "In5.Cu" signal "L6GND")
		(14 "In6.Cu" signal "L7VCC")
		(16 "In7.Cu" signal "L8VCC")
		(18 "In8.Cu" signal "L9GND")
		(20 "In9.Cu" signal "L10")
		(22 "In10.Cu" signal "L11GND")
		(24 "In11.Cu" signal "L12")
		(26 "In12.Cu" signal "L13GND")
		(2 "B.Cu" signal "BOTTOM")
		(9 "F.Adhes" user "F.Adhesive")
		(11 "B.Adhes" user "B.Adhesive")
		(13 "F.Paste" user "Package Geometry/Pastemask Top")
		(15 "B.Paste" user "Package Geometry/Pastemask Bottom")
		(5 "F.SilkS" user "Ref Des/Silkscreen Top")
		(7 "B.SilkS" user "Ref Des/Silkscreen Bottom")
		(1 "F.Mask" user "Board Geometry/Soldermask Top")
		(3 "B.Mask" user "Board Geometry/Soldermask Bottom")
		(17 "Dwgs.User" user "User.Drawings")
		(19 "Cmts.User" user "User.Comments")
		(21 "Eco1.User" user "User.Eco1")
		(23 "Eco2.User" user "User.Eco2")
		(25 "Edge.Cuts" user "Board Geometry/Outline")
		(27 "Margin" user)
		(31 "F.CrtYd" user "Package Geometry/Place Bound Top")
		(29 "B.CrtYd" user "Package Geometry/Place Bound Bottom")
		(35 "F.Fab" user "Ref Des/Assembly Top")
		(33 "B.Fab" user "Ref Des/Assembly Bottom")
	)
	(footprint ""
		(layer "B.Cu")
		(at 440.4233 -147.956016 180)
		(property "Reference" "R25W169"
			(at 0.8382 -0.67818 180)
			(unlocked yes)
			(layer "B.SilkS")
			(effects
				(font
					(size 0.4064 0.254)
					(thickness 0.1524)
				)
				(justify left mirror)
			)
		)
		(property "Value" ""
			(at 0 0 0)
			(layer "B.Fab")
			(effects
				(font
					(size 1.27 1.27)
				)
				(justify mirror)
			)
		)
		(duplicate_pad_numbers_are_jumpers no)
		(fp_poly
			(pts
				(xy 0.2794 -0.1016) (xy -0.2794 -0.1016) (xy -0.2794 0.9906) (xy 0.2794 0.9906)
			)
			(stroke
				(width 0)
				(type default)
			)
			(fill no)
			(layer "B.CrtYd")
		)
		(fp_line
			(start 0.2794 0.9906)
			(end -0.2794 0.9906)
			(stroke
				(width 0.1)
				(type default)
			)
			(layer "B.Fab")
		)
		(fp_line
			(start 0.2794 -0.1016)
			(end 0.2794 0.9906)
			(stroke
				(width 0.1)
				(type default)
			)
			(layer "B.Fab")
		)
		(fp_line
			(start -0.2794 0.9906)
			(end -0.2794 -0.1016)
			(stroke
				(width 0.1)
				(type default)
			)
			(layer "B.Fab")
		)
		(fp_line
			(start -0.2794 -0.1016)
			(end 0.2794 -0.1016)
			(stroke
				(width 0.1)
				(type default)
			)
			(layer "B.Fab")
		)
		(pad "1" smd rect
			(at 0 0)
			(size 0.508 0.508)
			(layers "B.Cu" "B.Mask" "B.Paste")
			(net "JTAG_BMC_TCK1")
		)
		(pad "2" smd rect
			(at 0 0.889)
			(size 0.508 0.508)
			(layers "B.Cu" "B.Mask" "B.Paste")
			(net "GND")
		)
		(zone
			(layer "B.Cu")
			(hatch none 0.5)
			(connect_pads
				(clearance 0)
			)
			(min_thickness 0.25)
			(keepout
				(tracks not_allowed)
				(vias allowed)
				(pads allowed)
				(copperpour not_allowed)
				(footprints allowed)
			)
			(placement
				(enabled no)
				(sheetname "")
			)
			(fill
				(thermal_gap 0.5)
				(thermal_bridge_width 0.5)
				(island_removal_mode 0)
			)
			(polygon
				(pts
					(xy 440.1693 -148.591016) (xy 440.6773 -148.591016) (xy 440.6773 -148.210016) (xy 440.1693 -148.210016)
				)
			)
		)
		(zone
			(layer "B.Cu")
			(hatch none 0.5)
			(connect_pads
				(clearance 0)
			)
			(min_thickness 0.25)
			(keepout
				(tracks allowed)
				(vias not_allowed)
				(pads allowed)
				(copperpour not_allowed)
				(footprints allowed)
			)
			(placement
				(enabled no)
				(sheetname "")
			)
			(fill
				(thermal_gap 0.5)
				(thermal_bridge_width 0.5)
				(island_removal_mode 0)
			)
			(polygon
				(pts
					(xy 440.1693 -148.210016) (xy 440.6773 -148.210016) (xy 440.6773 -148.591016) (xy 440.1693 -148.591016)
				)
			)
		)
	)
	(footprint ""
		(layer "B.Cu")
		(at 377.698 -20.32 180)
		(property "Reference" "RN8F4"
			(at 0.8382 -0.67818 180)
			(unlocked yes)
			(layer "B.SilkS")
			(effects
				(font
					(size 0.4064 0.254)
					(thickness 0.1524)
				)
				(justify left mirror)
			)
		)
		(property "Value" ""
			(at 0 0 0)
			(layer "B.Fab")
			(effects
				(font
					(size 1.27 1.27)
				)
				(justify mirror)
			)
		)
		(duplicate_pad_numbers_are_jumpers no)
		(fp_poly
			(pts
				(xy 0.2794 -0.1016) (xy -0.2794 -0.1016) (xy -0.2794 0.9906) (xy 0.2794 0.9906)
			)
			(stroke
				(width 0)
				(type default)
			)
			(fill no)
			(layer "B.CrtYd")
		)
		(fp_line
			(start 0.2794 0.9906)
			(end -0.2794 0.9906)
			(stroke
				(width 0.1)
				(type default)
			)
			(layer "B.Fab")
		)
		(fp_line
			(start 0.2794 -0.1016)
			(end 0.2794 0.9906)
			(stroke
				(width 0.1)
				(type default)
			)
			(layer "B.Fab")
		)
		(fp_line
			(start -0.2794 0.9906)
			(end -0.2794 -0.1016)
			(stroke
				(width 0.1)
				(type default)
			)
			(layer "B.Fab")
		)
		(fp_line
			(start -0.2794 -0.1016)
			(end 0.2794 -0.1016)
			(stroke
				(width 0.1)
				(type default)
			)
			(layer "B.Fab")
		)
		(pad "1" smd rect
			(at 0 0)
			(size 0.508 0.508)
			(layers "B.Cu" "B.Mask" "B.Paste")
			(net "P3V3_STBY")
		)
		(pad "2" smd rect
			(at 0 0.889)
			(size 0.508 0.508)
			(layers "B.Cu" "B.Mask" "B.Paste")
			(net "PU_TPM_SPI_FLASH_RESET_2_N")
		)
		(zone
			(layer "B.Cu")
			(hatch none 0.5)
			(connect_pads
				(clearance 0)
			)
			(min_thickness 0.25)
			(keepout
				(tracks not_allowed)
				(vias allowed)
				(pads allowed)
				(copperpour not_allowed)
				(footprints allowed)
			)
			(placement
				(enabled no)
				(sheetname "")
			)
			(fill
				(thermal_gap 0.5)
				(thermal_bridge_width 0.5)
				(island_removal_mode 0)
			)
			(polygon
				(pts
					(xy 377.444 -20.955) (xy 377.952 -20.955) (xy 377.952 -20.574) (xy 377.444 -20.574)
				)
			)
		)
		(zone
			(layer "B.Cu")
			(hatch none 0.5)
			(connect_pads
				(clearance 0)
			)
			(min_thickness 0.25)
			(keepout
				(tracks allowed)
				(vias not_allowed)
				(pads allowed)
				(copperpour not_allowed)
				(footprints allowed)
			)
			(placement
				(enabled no)
				(sheetname "")
			)
			(fill
				(thermal_gap 0.5)
				(thermal_bridge_width 0.5)
				(island_removal_mode 0)
			)
			(polygon
				(pts
					(xy 377.444 -20.574) (xy 377.952 -20.574) (xy 377.952 -20.955) (xy 377.444 -20.955)
				)
			)
		)
	)
	(footprint ""
		(layer "B.Cu")
		(at 382.79705 -108.4834 -90)
		(property "Reference" "C3N16"
			(at 0 0 90)
			(layer "B.SilkS")
			(hide yes)
			(effects
				(font
					(size 1.27 1.27)
				)
				(justify mirror)
			)
		)
		(property "Value" ""
			(at 0 0 90)
			(layer "B.Fab")
			(effects
				(font
					(size 1.27 1.27)
				)
				(justify mirror)
			)
		)
		(duplicate_pad_numbers_are_jumpers no)
		(fp_rect
			(start 0.2794 0.9144)
			(end -0.2794 -0.1143)
			(stroke
				(width 0)
				(type default)
			)
			(fill no)
			(layer "B.CrtYd")
		)
		(fp_line
			(start -0.2794 0.9144)
			(end 0.2794 0.9144)
			(stroke
				(width 0.1)
				(type default)
			)
			(layer "B.Fab")
		)
		(fp_line
			(start 0.2794 0.9144)
			(end 0.2794 -0.1143)
			(stroke
				(width 0.1)
				(type default)
			)
			(layer "B.Fab")
		)
		(fp_line
			(start -0.2794 -0.1143)
			(end -0.2794 0.9144)
			(stroke
				(width 0.1)
				(type default)
			)
			(layer "B.Fab")
		)
		(fp_line
			(start 0.2794 -0.1143)
			(end -0.2794 -0.1143)
			(stroke
				(width 0.1)
				(type default)
			)
			(layer "B.Fab")
		)
		(pad "1" smd custom
			(at 0 0 180)
			(size 0.10414 0.10414)
			(layers "B.Cu" "B.Mask" "B.Paste")
			(net "PVNN_PCH_STBY")
			(options
				(clearance outline)
				(anchor circle)
			)
			(primitives
				(gr_poly
					(pts
						(xy -0.20828 -0.08636) (xy -0.20828 0.08636) (xy -0.08636 0.20828) (xy 0.086614 0.20828) (xy 0.20828 0.086614)
						(xy 0.20828 -0.08636) (xy 0.08636 -0.20828) (xy -0.08636 -0.20828)
					)
					(width 0)
					(fill yes)
				)
			)
		)
		(pad "2" smd custom
			(at 0 0.8001 180)
			(size 0.10414 0.10414)
			(layers "B.Cu" "B.Mask" "B.Paste")
			(net "GND")
			(options
				(clearance outline)
				(anchor circle)
			)
			(primitives
				(gr_poly
					(pts
						(xy -0.20828 -0.08636) (xy -0.20828 0.08636) (xy -0.08636 0.20828) (xy 0.086614 0.20828) (xy 0.20828 0.086614)
						(xy 0.20828 -0.08636) (xy 0.08636 -0.20828) (xy -0.08636 -0.20828)
					)
					(width 0)
					(fill yes)
				)
			)
		)
		(zone
			(layer "B.Cu")
			(hatch none 0.5)
			(connect_pads
				(clearance 0)
			)
			(min_thickness 0.25)
			(keepout
				(tracks allowed)
				(vias not_allowed)
				(pads allowed)
				(copperpour not_allowed)
				(footprints allowed)
			)
			(placement
				(enabled no)
				(sheetname "")
			)
			(fill
				(thermal_gap 0.5)
				(thermal_bridge_width 0.5)
				(island_removal_mode 0)
			)
			(polygon
				(pts
					(xy 382.5875 -108.39577) (xy 382.2065 -108.39577) (xy 382.2065 -108.57103) (xy 382.5875 -108.571284)
				)
			)
		)
		(zone
			(layer "B.Cu")
			(hatch none 0.5)
			(connect_pads
				(clearance 0)
			)
			(min_thickness 0.25)
			(keepout
				(tracks not_allowed)
				(vias allowed)
				(pads allowed)
				(copperpour not_allowed)
				(footprints allowed)
			)
			(placement
				(enabled no)
				(sheetname "")
			)
			(fill
				(thermal_gap 0.5)
				(thermal_bridge_width 0.5)
				(island_removal_mode 0)
			)
			(polygon
				(pts
					(xy 382.5875 -108.39577) (xy 382.2065 -108.39577) (xy 382.2065 -108.57103) (xy 382.5875 -108.571284)
				)
			)
		)
	)
)
